# T6G (Grand Teton) — schematic netlist excerpt (pin names and nets, part order shuffled) for the footprints in the layout excerpt that follows; sources: Cadence DE-HDL packaged netlist, KiCad conversion of 04192023_DAF0TMB3IC0_F0TG_MB_C_brd_V02_OCP.brd

R1629  Q_RES  1K 1% CHIP  pkg 0402LF  page 172 : A = HDT_CPU0_HDT_CONN_TESTEN ; B = GND
C1525  Q_CAP_DIFFBUS  DIFF BUS_0.22UF 6.3V 20% X6S  pkg C0201  page 67 : \1\ = P5E_CPU1_P3_TX_C_DP<11> ; \2\ = P5E_CPU1_P3_TX_DP<11>
R343  Q_RES  49.9 1% EMPTY  pkg 0201LF  page 180 : A = USB2_CPU0_P0_R2_DP ; B = GND

(kicad_pcb
	(version 20260206)
	(generator "pcbnew")
	(generator_version "10.0")
	(general
		(thickness 1.6)
		(legacy_teardrops no)
	)
	(paper "A4")
	(title_block
		(title "04192023_DAF0TMB3IC0_F0TG_MB_C_brd_V02_OCP.brd")
		(comment 1 "Grand Teton / footprints 2395-2397 of 8354")
	)
	(layers
		(0 "F.Cu" signal "TOP")
		(4 "In1.Cu" signal "GND")
		(6 "In2.Cu" signal "IN1")
		(8 "In3.Cu" signal "GND1")
		(10 "In4.Cu" signal "IN2")
		(12 "In5.Cu" signal "GND2")
		(14 "In6.Cu" signal "IN3")
		(16 "In7.Cu" signal "GND3")
		(18 "In8.Cu" signal "VCC")
		(20 "In9.Cu" signal "VCC1")
		(22 "In10.Cu" signal "GND4")
		(24 "In11.Cu" signal "IN4")
		(26 "In12.Cu" signal "GND5")
		(28 "In13.Cu" signal "IN5")
		(30 "In14.Cu" signal "GND6")
		(32 "In15.Cu" signal "IN6")
		(34 "In16.Cu" signal "GND7")
		(2 "B.Cu" signal "BOTTOM")
		(9 "F.Adhes" user "F.Adhesive")
		(11 "B.Adhes" user "B.Adhesive")
		(13 "F.Paste" user "Package Geometry/Pastemask Top")
		(15 "B.Paste" user "Package Geometry/Pastemask Bottom")
		(5 "F.SilkS" user "Ref Des/Silkscreen Top")
		(7 "B.SilkS" user "Ref Des/Silkscreen Bottom")
		(1 "F.Mask" user "Board Geometry/Soldermask Top")
		(3 "B.Mask" user "Board Geometry/Soldermask Bottom")
		(17 "Dwgs.User" user "User.Drawings")
		(19 "Cmts.User" user "User.Comments")
		(21 "Eco1.User" user "User.Eco1")
		(23 "Eco2.User" user "User.Eco2")
		(25 "Edge.Cuts" user "Board Geometry/Outline")
		(27 "Margin" user)
		(31 "F.CrtYd" user "Package Geometry/Place Bound Top")
		(29 "B.CrtYd" user "Package Geometry/Place Bound Bottom")
		(35 "F.Fab" user "Ref Des/Assembly Top")
		(33 "B.Fab" user "Ref Des/Assembly Bottom")
	)
	(footprint ""
		(layer "F.Cu")
		(at 386.211826 -63.3095 180)
		(property "Reference" "R1629"
			(at 0 0 180)
			(layer "F.SilkS")
			(hide yes)
			(effects
				(font
					(size 1.27 1.27)
				)
			)
		)
		(property "Value" ""
			(at 0 0 180)
			(layer "F.Fab")
			(effects
				(font
					(size 1.27 1.27)
				)
			)
		)
		(duplicate_pad_numbers_are_jumpers no)
		(fp_line
			(start 0.7874 0.4064)
			(end -0.7874 0.4064)
			(stroke
				(width 0.1524)
				(type default)
			)
			(layer "F.SilkS")
		)
		(fp_line
			(start 0.7874 -0.4064)
			(end 0.7874 0.4064)
			(stroke
				(width 0.1524)
				(type default)
			)
			(layer "F.SilkS")
		)
		(fp_line
			(start -0.7874 0.4064)
			(end -0.7874 -0.4064)
			(stroke
				(width 0.1524)
				(type default)
			)
			(layer "F.SilkS")
		)
		(fp_line
			(start -0.7874 -0.4064)
			(end 0.7874 -0.4064)
			(stroke
				(width 0.1524)
				(type default)
			)
			(layer "F.SilkS")
		)
		(fp_line
			(start 0.67945 0.3048)
			(end 0.120396 0.3048)
			(stroke
				(width 0.1)
				(type default)
			)
			(layer "F.Fab")
		)
		(fp_line
			(start 0.67945 -0.3048)
			(end 0.67945 0.3048)
			(stroke
				(width 0.1)
				(type default)
			)
			(layer "F.Fab")
		)
		(fp_line
			(start 0.12065 -0.2794)
			(end 0.12065 -0.3048)
			(stroke
				(width 0.1)
				(type default)
			)
			(layer "F.Fab")
		)
		(fp_line
			(start 0.12065 -0.3048)
			(end 0.67945 -0.3048)
			(stroke
				(width 0.1)
				(type default)
			)
			(layer "F.Fab")
		)
		(fp_line
			(start 0.120396 0.3048)
			(end 0.120396 0.2794)
			(stroke
				(width 0.1)
				(type default)
			)
			(layer "F.Fab")
		)
		(fp_line
			(start 0.120396 0.2794)
			(end -0.12065 0.2794)
			(stroke
				(width 0.1)
				(type default)
			)
			(layer "F.Fab")
		)
		(fp_line
			(start -0.12065 0.3048)
			(end -0.67945 0.3048)
			(stroke
				(width 0.1)
				(type default)
			)
			(layer "F.Fab")
		)
		(fp_line
			(start -0.12065 0.2794)
			(end -0.12065 0.3048)
			(stroke
				(width 0.1)
				(type default)
			)
			(layer "F.Fab")
		)
		(fp_line
			(start -0.12065 -0.2794)
			(end 0.12065 -0.2794)
			(stroke
				(width 0.1)
				(type default)
			)
			(layer "F.Fab")
		)
		(fp_line
			(start -0.12065 -0.305054)
			(end -0.12065 -0.2794)
			(stroke
				(width 0.1)
				(type default)
			)
			(layer "F.Fab")
		)
		(fp_line
			(start -0.67945 0.3048)
			(end -0.67945 -0.305054)
			(stroke
				(width 0.1)
				(type default)
			)
			(layer "F.Fab")
		)
		(fp_line
			(start -0.67945 -0.305054)
			(end -0.12065 -0.305054)
			(stroke
				(width 0.1)
				(type default)
			)
			(layer "F.Fab")
		)
		(pad "1" smd circle
			(at -0.40005 0 180)
			(size 0 0)
			(layers "F.Cu" "F.Mask" "F.Paste")
			(net "HDT_CPU0_HDT_CONN_TESTEN")
		)
		(pad "2" smd circle
			(at 0.40005 0 180)
			(size 0 0)
			(layers "F.Cu" "F.Mask" "F.Paste")
			(net "GND")
		)
	)
	(footprint ""
		(layer "F.Cu")
		(at 103.998522 -33.185354 90)
		(property "Reference" "R343"
			(at 0 0 90)
			(layer "F.SilkS")
			(hide yes)
			(effects
				(font
					(size 1.27 1.27)
				)
			)
		)
		(property "Value" ""
			(at 0 0 90)
			(layer "F.Fab")
			(effects
				(font
					(size 1.27 1.27)
				)
			)
		)
		(duplicate_pad_numbers_are_jumpers no)
		(fp_line
			(start 0.32512 -0.175006)
			(end 0.32512 0.175006)
			(stroke
				(width 0.1)
				(type default)
			)
			(layer "F.Fab")
		)
		(fp_line
			(start -0.32512 -0.175006)
			(end 0.32512 -0.175006)
			(stroke
				(width 0.1)
				(type default)
			)
			(layer "F.Fab")
		)
		(fp_line
			(start 0.32512 0.175006)
			(end -0.32512 0.175006)
			(stroke
				(width 0.1)
				(type default)
			)
			(layer "F.Fab")
		)
		(fp_line
			(start -0.32512 0.175006)
			(end -0.32512 -0.175006)
			(stroke
				(width 0.1)
				(type default)
			)
			(layer "F.Fab")
		)
		(pad "1" smd rect
			(at -0.2667 0 90)
			(size 0.3048 0.381)
			(layers "F.Cu" "F.Mask" "F.Paste")
			(net "USB2_CPU0_P0_R2_DP")
		)
		(pad "2" smd rect
			(at 0.2667 0 270)
			(size 0.3048 0.381)
			(layers "F.Cu" "F.Mask" "F.Paste")
			(net "GND")
		)
	)
	(footprint ""
		(layer "F.Cu")
		(at 130.511296 -373.03583 -90)
		(property "Reference" "C1525"
			(at 0 0 270)
			(layer "F.SilkS")
			(hide yes)
			(effects
				(font
					(size 1.27 1.27)
				)
			)
		)
		(property "Value" ""
			(at 0 0 270)
			(layer "F.Fab")
			(effects
				(font
					(size 1.27 1.27)
				)
			)
		)
		(duplicate_pad_numbers_are_jumpers no)
		(fp_line
			(start -0.299974 0.150114)
			(end -0.299974 -0.150114)
			(stroke
				(width 0.1)
				(type default)
			)
			(layer "F.Fab")
		)
		(fp_line
			(start 0.299974 0.150114)
			(end -0.299974 0.150114)
			(stroke
				(width 0.1)
				(type default)
			)
			(layer "F.Fab")
		)
		(fp_line
			(start -0.299974 -0.150114)
			(end 0.299974 -0.150114)
			(stroke
				(width 0.1)
				(type default)
			)
			(layer "F.Fab")
		)
		(fp_line
			(start 0.299974 -0.150114)
			(end 0.299974 0.150114)
			(stroke
				(width 0.1)
				(type default)
			)
			(layer "F.Fab")
		)
		(pad "1" smd rect
			(at -0.2667 0 270)
			(size 0.3048 0.381)
			(layers "F.Cu" "F.Mask" "F.Paste")
			(net "P5E_CPU1_P3_TX_C_DP<11>")
		)
		(pad "2" smd rect
			(at 0.2667 0 270)
			(size 0.3048 0.381)
			(layers "F.Cu" "F.Mask" "F.Paste")
			(net "P5E_CPU1_P3_TX_DP<11>")
		)
	)
)
